M48
;Layer_Color=9474304
;FILE_FORMAT=4:4
METRIC,LZ
;TYPE=PLATED
T1F00S00C0.3000
T2F00S00C0.3000
T3F00S00C1.0200
T4F00S00C1.0900
T5F00S00C3.7000
;TYPE=NON_PLATED
T6F00S00C3.0000
%
T01
X00027078Y00093504
X00041916
X0005509
X00072036Y00102261
X0011425Y00104
X0012961Y00095565
X00169161Y00102103
X00183138
X00444999Y00421418
X00445113Y0047275
X00475Y0044775
X00440352Y00374949
X00363284Y00389088
X00345269Y00393919
X00342703Y00406495
X003315Y00400274
X00327Y00392924
X0029725Y003855
X002645Y00375775
X00259492Y00353693
X00274414Y00352344
X00267761Y0031925
X00272892Y0029475
X00258Y0029225
X00244245Y00292311
X0023225Y00291385
X00241197Y0030875
X002435Y00257561
Y00244381
X00258
X002735
X00293674
X0028925Y002695
X00332Y00243
X0034475
X0035025Y00211521
X00391579Y00185091
X00403
X00403Y0017375
X0039325Y002425
X00403Y002635
X00403Y00274431
X00414482
X00363962Y00297432
X0037575Y00322588
X0035475Y003395
X00343677Y00360775
X0033475Y00326
X00206542Y00332843
X00193292Y00330805
X00142Y0035975
X0010375Y00358378
X0009561Y00353378
X0010925Y00377668
X000515Y00390689
X00055967Y00354628
X00052108Y0025406
X00084365Y002515
X00083952Y00262552
X00066659Y00224
X00065619Y002155
X00065473Y00198873
X00052118Y0019729
X000665Y00162527
X00077704
X00102727
X0011525
X00130429Y0018125
X00142Y00178086
X0015975Y00177787
X0016Y001865
X001714Y00173
X00184407Y00173689
X00212Y00174955
X00224129Y00188721
X00228424Y00209744
X00243939
X00258939
Y00182705
X00243939Y00182955
X00270189Y00187644
X00279206Y00190705
X00172Y0014775
X0015875Y0013285
X00172498Y0011325
X001295Y001065
X00091Y001085
X00091005Y0011925
X0005509Y001065
X0014675Y0023031
X00145319Y00249
X00145Y00264
X00156752Y00276869
X00206956Y00397805
X00207706Y004328
X0017575
X00177Y0049275
X002095Y0048975
X0013975Y00463508
X0011708Y00493963
X00087Y0047525
X00270921Y004375
X0028525Y0044603
X002945Y0045475
X003635Y00449682
X003725Y0044
X00017785Y0039796
X000175Y00388019
Y0037771
Y0036771
Y0035746
X00017462Y00347587
X00008744Y00354901
X00022702Y002465
T02
X001495Y0006325
X0016175Y0006475
X0017325Y0006502
X00183138Y00069052
X00192905Y0006925
X00307Y0007425
X003075Y000845
X0030632Y00095089
X0030682Y00105339
X0031957Y00105089
X0031907Y00094839
X0032025Y0008425
X0031975Y00074
X0031957Y00063339
X0031907Y00053089
X0032075Y0004585
X0032025Y000356
X00331693Y00035155
X00332193Y00045405
X00330513Y00052643
X00331013Y00062893
X00331194Y00073554
X00331693Y00083804
X00330513Y00094393
X00331013Y00104643
X0034257Y00105089
X00351161Y0010307
X00361411Y0010257
X00361161Y0008982
X00350911Y0009032
X0034207Y00094839
X0034325Y0008425
X0034275Y00074
X00350161Y0007507
X00360411Y0007457
X00360857Y00063014
X00350607Y00063513
X0034257Y00063339
X0034207Y00053089
X0034375Y0004585
X0034325Y000356
X00349911Y0003932
X00360161Y0003882
X00360411Y0005157
X00350161Y0005207
X0030632Y00053339
X00308Y000461
X003075Y0003585
X0030682Y00063589
X00307Y00116
X003075Y0012625
X0032025Y00126
X0031975Y0011575
X00331194Y00115304
X00331693Y00125554
X0034325Y00126
X00351161Y0012607
X00361411Y0012557
X00361857Y00114014
X00351607Y00114514
X0034275Y0011575
X00315Y00203311
X0031525Y00392363
X00391028Y00361264
X003515Y0048875
X00298715Y0048919
X002415Y0047875
X00234398Y0042269
X00223373Y00415288
X00220968Y00339
X00069Y0046325
T03
X0005965Y00179
X0003425
T04
X00051Y00051
X00457
Y00254
Y00457
X00192Y00484
X00162
X00132
X00102
X00072
X00051Y00457
T05
X00095Y00071
X00406Y00041
X00413Y00452
X00095Y00437
T06
X00465Y00138
Y00349
M30
